(kicad_pcb
	(version 20260206)
	(generator "pcbnew")
	(generator_version "10.0")
	(general
		(thickness 2.5)
		(legacy_teardrops no)
	)
	(paper "A4")
	(layers
		(0 "F.Cu" signal)
		(2 "B.Cu" signal)
		(9 "F.Adhes" user)
		(11 "B.Adhes" user)
		(13 "F.Paste" user)
		(15 "B.Paste" user)
		(5 "F.SilkS" user)
		(7 "B.SilkS" user)
		(1 "F.Mask" user)
		(3 "B.Mask" user)
		(17 "Dwgs.User" user)
		(19 "Cmts.User" user)
		(21 "Eco1.User" user)
		(23 "Eco2.User" user)
		(25 "Edge.Cuts" user)
		(27 "Margin" user)
		(31 "F.CrtYd" user)
		(29 "B.CrtYd" user)
		(35 "F.Fab" user)
		(33 "B.Fab" user)
	)
	(setup
		(pad_to_mask_clearance 0.051)
		(solder_mask_min_width 0.25)
		(allow_soldermask_bridges_in_footprints no)
		(tenting
			(front yes)
			(back yes)
		)
		(covering
			(front no)
			(back no)
		)
		(plugging
			(front no)
			(back no)
		)
		(capping no)
		(filling no)
		(aux_axis_origin 4.99872 144.99844)
		(pcbplotparams
			(layerselection 0x00000000_00000000_5555555f_f755ffff)
			(plot_on_all_layers_selection 0x00000000_00000000_00000000_00000000)
			(disableapertmacros no)
			(usegerberextensions no)
			(usegerberattributes no)
			(usegerberadvancedattributes no)
			(creategerberjobfile no)
			(dashed_line_dash_ratio 12)
			(dashed_line_gap_ratio 3)
			(svgprecision 4)
			(plotframeref no)
			(mode 1)
			(useauxorigin yes)
			(pdf_front_fp_property_popups yes)
			(pdf_back_fp_property_popups yes)
			(pdf_metadata yes)
			(pdf_single_document no)
			(dxfpolygonmode yes)
			(dxfimperialunits yes)
			(dxfusepcbnewfont yes)
			(psnegative no)
			(psa4output no)
			(plot_black_and_white yes)
			(sketchpadsonfab no)
			(plotpadnumbers no)
			(hidednponfab no)
			(sketchdnponfab yes)
			(crossoutdnponfab yes)
			(subtractmaskfromsilk no)
			(outputformat 1)
			(mirror no)
			(drillshape 0)
			(scaleselection 1)
			(outputdirectory "../production_files/drill/")
		)
	)
	(footprint "discovery:CONN_02x03_4.2mm"
		(layer "F.Cu")
		(at 28 93.5 -90)
		(property "Reference" "J2"
			(at 1.0668 -10.6172 90)
			(layer "F.SilkS")
			(effects
				(font
					(size 1 1)
					(thickness 0.15)
				)
			)
		)
		(property "Value" "Conn_02x03_PCIe"
			(at 6.8961 -11.176 270)
			(layer "F.Fab")
			(effects
				(font
					(size 0.75 0.75)
					(thickness 0.125)
				)
			)
		)
		(attr through_hole)
		(duplicate_pad_numbers_are_jumpers no)
		(fp_line
			(start 0 0)
			(end 13.8 0)
			(stroke
				(width 0.1)
				(type solid)
			)
			(layer "F.SilkS")
		)
		(fp_line
			(start 13.8 0)
			(end 13.8 -9.6)
			(stroke
				(width 0.1)
				(type solid)
			)
			(layer "F.SilkS")
		)
		(fp_line
			(start 0 -9.6)
			(end 0 0)
			(stroke
				(width 0.1)
				(type solid)
			)
			(layer "F.SilkS")
		)
		(fp_line
			(start 5.9 -9.6)
			(end 5.9 -10.4)
			(stroke
				(width 0.1)
				(type solid)
			)
			(layer "F.SilkS")
		)
		(fp_line
			(start 13.8 -9.6)
			(end 0 -9.6)
			(stroke
				(width 0.1)
				(type solid)
			)
			(layer "F.SilkS")
		)
		(fp_line
			(start 5.9 -10.4)
			(end 7.9 -10.4)
			(stroke
				(width 0.1)
				(type solid)
			)
			(layer "F.SilkS")
		)
		(fp_line
			(start 7.9 -10.4)
			(end 7.9 -9.6)
			(stroke
				(width 0.1)
				(type solid)
			)
			(layer "F.SilkS")
		)
		(fp_line
			(start -4 0.05)
			(end 17.8 0.05)
			(stroke
				(width 0.1)
				(type solid)
			)
			(layer "F.CrtYd")
		)
		(fp_line
			(start 17.8 0.05)
			(end 17.8 -10.45)
			(stroke
				(width 0.1)
				(type solid)
			)
			(layer "F.CrtYd")
		)
		(fp_line
			(start -4 -10.45)
			(end -4 0.05)
			(stroke
				(width 0.1)
				(type solid)
			)
			(layer "F.CrtYd")
		)
		(fp_line
			(start 17.8 -10.45)
			(end -4 -10.45)
			(stroke
				(width 0.1)
				(type solid)
			)
			(layer "F.CrtYd")
		)
		(pad "" np_thru_hole circle
			(at -2 -7.1 270)
			(size 4 4)
			(drill 3.03)
			(layers "*.Cu" "*.Mask")
		)
		(pad "" np_thru_hole circle
			(at 15.8 -7.1 270)
			(size 4 4)
			(drill 3.03)
			(layers "*.Cu" "*.Mask")
		)
		(pad "1" thru_hole circle
			(at 11.1 -2.9 270)
			(size 2.5 2.5)
			(drill 1.85)
			(layers "*.Cu" "*.Mask")
			(remove_unused_layers no)
			(net "+12V")
		)
		(pad "2" thru_hole circle
			(at 6.9 -2.9 270)
			(size 2.5 2.5)
			(drill 1.85)
			(layers "*.Cu" "*.Mask")
			(remove_unused_layers no)
			(net "+12V")
		)
		(pad "3" thru_hole circle
			(at 2.7 -2.9 270)
			(size 2.5 2.5)
			(drill 1.85)
			(layers "*.Cu" "*.Mask")
			(remove_unused_layers no)
			(net "+12V")
		)
		(pad "4" thru_hole circle
			(at 11.1 -7.1 270)
			(size 2.5 2.5)
			(drill 1.85)
			(layers "*.Cu" "*.Mask")
			(remove_unused_layers no)
			(net "GND")
		)
		(pad "5" thru_hole circle
			(at 6.9 -7.1 270)
			(size 2.5 2.5)
			(drill 1.85)
			(layers "*.Cu" "*.Mask")
			(remove_unused_layers no)
			(net "GND")
		)
		(pad "6" thru_hole circle
			(at 2.7 -7.1 270)
			(size 2.5 2.5)
			(drill 1.85)
			(layers "*.Cu" "*.Mask")
			(remove_unused_layers no)
			(net "GND")
		)
	)
	(footprint "discovery:CONN_02x03_4.2mm"
		(layer "F.Cu")
		(at 18 107.3 90)
		(property "Reference" "J4"
			(at 12.71672 -10.37492 90)
			(layer "F.SilkS")
			(effects
				(font
					(size 1 1)
					(thickness 0.15)
				)
			)
		)
		(property "Value" "Conn_02x03_PCIe"
			(at 6.8961 -11.176 90)
			(layer "F.Fab")
			(effects
				(font
					(size 0.75 0.75)
					(thickness 0.125)
				)
			)
		)
		(attr through_hole)
		(duplicate_pad_numbers_are_jumpers no)
		(fp_line
			(start 7.9 -10.4)
			(end 7.9 -9.6)
			(stroke
				(width 0.1)
				(type solid)
			)
			(layer "F.SilkS")
		)
		(fp_line
			(start 5.9 -10.4)
			(end 7.9 -10.4)
			(stroke
				(width 0.1)
				(type solid)
			)
			(layer "F.SilkS")
		)
		(fp_line
			(start 13.8 -9.6)
			(end 0 -9.6)
			(stroke
				(width 0.1)
				(type solid)
			)
			(layer "F.SilkS")
		)
		(fp_line
			(start 5.9 -9.6)
			(end 5.9 -10.4)
			(stroke
				(width 0.1)
				(type solid)
			)
			(layer "F.SilkS")
		)
		(fp_line
			(start 0 -9.6)
			(end 0 0)
			(stroke
				(width 0.1)
				(type solid)
			)
			(layer "F.SilkS")
		)
		(fp_line
			(start 13.8 0)
			(end 13.8 -9.6)
			(stroke
				(width 0.1)
				(type solid)
			)
			(layer "F.SilkS")
		)
		(fp_line
			(start 0 0)
			(end 13.8 0)
			(stroke
				(width 0.1)
				(type solid)
			)
			(layer "F.SilkS")
		)
		(fp_line
			(start 17.8 -10.45)
			(end -4 -10.45)
			(stroke
				(width 0.1)
				(type solid)
			)
			(layer "F.CrtYd")
		)
		(fp_line
			(start -4 -10.45)
			(end -4 0.05)
			(stroke
				(width 0.1)
				(type solid)
			)
			(layer "F.CrtYd")
		)
		(fp_line
			(start 17.8 0.05)
			(end 17.8 -10.45)
			(stroke
				(width 0.1)
				(type solid)
			)
			(layer "F.CrtYd")
		)
		(fp_line
			(start -4 0.05)
			(end 17.8 0.05)
			(stroke
				(width 0.1)
				(type solid)
			)
			(layer "F.CrtYd")
		)
		(pad "" np_thru_hole circle
			(at -2 -7.1 90)
			(size 4 4)
			(drill 3.03)
			(layers "*.Cu" "*.Mask")
		)
		(pad "" np_thru_hole circle
			(at 15.8 -7.1 90)
			(size 4 4)
			(drill 3.03)
			(layers "*.Cu" "*.Mask")
		)
		(pad "1" thru_hole circle
			(at 11.1 -2.9 90)
			(size 2.5 2.5)
			(drill 1.85)
			(layers "*.Cu" "*.Mask")
			(remove_unused_layers no)
			(net "+12V")
		)
		(pad "2" thru_hole circle
			(at 6.9 -2.9 90)
			(size 2.5 2.5)
			(drill 1.85)
			(layers "*.Cu" "*.Mask")
			(remove_unused_layers no)
			(net "+12V")
		)
		(pad "3" thru_hole circle
			(at 2.7 -2.9 90)
			(size 2.5 2.5)
			(drill 1.85)
			(layers "*.Cu" "*.Mask")
			(remove_unused_layers no)
			(net "+12V")
		)
		(pad "4" thru_hole circle
			(at 11.1 -7.1 90)
			(size 2.5 2.5)
			(drill 1.85)
			(layers "*.Cu" "*.Mask")
			(remove_unused_layers no)
			(net "GND")
		)
		(pad "5" thru_hole circle
			(at 6.9 -7.1 90)
			(size 2.5 2.5)
			(drill 1.85)
			(layers "*.Cu" "*.Mask")
			(remove_unused_layers no)
			(net "GND")
		)
		(pad "6" thru_hole circle
			(at 2.7 -7.1 90)
			(size 2.5 2.5)
			(drill 1.85)
			(layers "*.Cu" "*.Mask")
			(remove_unused_layers no)
			(net "GND")
		)
	)
	(footprint "discovery:CONN_02x03_4.2mm"
		(layer "F.Cu")
		(at 18 136.1326 90)
		(property "Reference" "J5"
			(at 12.74572 -10.42064 90)
			(layer "F.SilkS")
			(effects
				(font
					(size 1 1)
					(thickness 0.15)
				)
			)
		)
		(property "Value" "Conn_02x03_PCIe"
			(at 6.8961 -11.176 90)
			(layer "F.Fab")
			(effects
				(font
					(size 0.75 0.75)
					(thickness 0.125)
				)
			)
		)
		(attr through_hole)
		(duplicate_pad_numbers_are_jumpers no)
		(fp_line
			(start 7.9 -10.4)
			(end 7.9 -9.6)
			(stroke
				(width 0.1)
				(type solid)
			)
			(layer "F.SilkS")
		)
		(fp_line
			(start 5.9 -10.4)
			(end 7.9 -10.4)
			(stroke
				(width 0.1)
				(type solid)
			)
			(layer "F.SilkS")
		)
		(fp_line
			(start 13.8 -9.6)
			(end 0 -9.6)
			(stroke
				(width 0.1)
				(type solid)
			)
			(layer "F.SilkS")
		)
		(fp_line
			(start 5.9 -9.6)
			(end 5.9 -10.4)
			(stroke
				(width 0.1)
				(type solid)
			)
			(layer "F.SilkS")
		)
		(fp_line
			(start 0 -9.6)
			(end 0 0)
			(stroke
				(width 0.1)
				(type solid)
			)
			(layer "F.SilkS")
		)
		(fp_line
			(start 13.8 0)
			(end 13.8 -9.6)
			(stroke
				(width 0.1)
				(type solid)
			)
			(layer "F.SilkS")
		)
		(fp_line
			(start 0 0)
			(end 13.8 0)
			(stroke
				(width 0.1)
				(type solid)
			)
			(layer "F.SilkS")
		)
		(fp_line
			(start 17.8 -10.45)
			(end -4 -10.45)
			(stroke
				(width 0.1)
				(type solid)
			)
			(layer "F.CrtYd")
		)
		(fp_line
			(start -4 -10.45)
			(end -4 0.05)
			(stroke
				(width 0.1)
				(type solid)
			)
			(layer "F.CrtYd")
		)
		(fp_line
			(start 17.8 0.05)
			(end 17.8 -10.45)
			(stroke
				(width 0.1)
				(type solid)
			)
			(layer "F.CrtYd")
		)
		(fp_line
			(start -4 0.05)
			(end 17.8 0.05)
			(stroke
				(width 0.1)
				(type solid)
			)
			(layer "F.CrtYd")
		)
		(pad "" np_thru_hole circle
			(at -2 -7.1 90)
			(size 4 4)
			(drill 3.03)
			(layers "*.Cu" "*.Mask")
		)
		(pad "" np_thru_hole circle
			(at 15.8 -7.1 90)
			(size 4 4)
			(drill 3.03)
			(layers "*.Cu" "*.Mask")
		)
		(pad "1" thru_hole circle
			(at 11.1 -2.9 90)
			(size 2.5 2.5)
			(drill 1.85)
			(layers "*.Cu" "*.Mask")
			(remove_unused_layers no)
			(net "+12V")
		)
		(pad "2" thru_hole circle
			(at 6.9 -2.9 90)
			(size 2.5 2.5)
			(drill 1.85)
			(layers "*.Cu" "*.Mask")
			(remove_unused_layers no)
			(net "+12V")
		)
		(pad "3" thru_hole circle
			(at 2.7 -2.9 90)
			(size 2.5 2.5)
			(drill 1.85)
			(layers "*.Cu" "*.Mask")
			(remove_unused_layers no)
			(net "+12V")
		)
		(pad "4" thru_hole circle
			(at 11.1 -7.1 90)
			(size 2.5 2.5)
			(drill 1.85)
			(layers "*.Cu" "*.Mask")
			(remove_unused_layers no)
			(net "GND")
		)
		(pad "5" thru_hole circle
			(at 6.9 -7.1 90)
			(size 2.5 2.5)
			(drill 1.85)
			(layers "*.Cu" "*.Mask")
			(remove_unused_layers no)
			(net "GND")
		)
		(pad "6" thru_hole circle
			(at 2.7 -7.1 90)
			(size 2.5 2.5)
			(drill 1.85)
			(layers "*.Cu" "*.Mask")
			(remove_unused_layers no)
			(net "GND")
		)
	)
	(footprint "discovery:CONN_02x03_4.2mm"
		(layer "F.Cu")
		(at 28 122.3326 -90)
		(property "Reference" "J6"
			(at 1.02108 -10.54196 270)
			(layer "F.SilkS")
			(effects
				(font
					(size 1 1)
					(thickness 0.15)
				)
			)
		)
		(property "Value" "Conn_02x03_PCIe"
			(at 6.8961 -11.176 270)
			(layer "F.Fab")
			(effects
				(font
					(size 0.75 0.75)
					(thickness 0.125)
				)
			)
		)
		(attr through_hole)
		(duplicate_pad_numbers_are_jumpers no)
		(fp_line
			(start 0 0)
			(end 13.8 0)
			(stroke
				(width 0.1)
				(type solid)
			)
			(layer "F.SilkS")
		)
		(fp_line
			(start 13.8 0)
			(end 13.8 -9.6)
			(stroke
				(width 0.1)
				(type solid)
			)
			(layer "F.SilkS")
		)
		(fp_line
			(start 0 -9.6)
			(end 0 0)
			(stroke
				(width 0.1)
				(type solid)
			)
			(layer "F.SilkS")
		)
		(fp_line
			(start 5.9 -9.6)
			(end 5.9 -10.4)
			(stroke
				(width 0.1)
				(type solid)
			)
			(layer "F.SilkS")
		)
		(fp_line
			(start 13.8 -9.6)
			(end 0 -9.6)
			(stroke
				(width 0.1)
				(type solid)
			)
			(layer "F.SilkS")
		)
		(fp_line
			(start 5.9 -10.4)
			(end 7.9 -10.4)
			(stroke
				(width 0.1)
				(type solid)
			)
			(layer "F.SilkS")
		)
		(fp_line
			(start 7.9 -10.4)
			(end 7.9 -9.6)
			(stroke
				(width 0.1)
				(type solid)
			)
			(layer "F.SilkS")
		)
		(fp_line
			(start -4 0.05)
			(end 17.8 0.05)
			(stroke
				(width 0.1)
				(type solid)
			)
			(layer "F.CrtYd")
		)
		(fp_line
			(start 17.8 0.05)
			(end 17.8 -10.45)
			(stroke
				(width 0.1)
				(type solid)
			)
			(layer "F.CrtYd")
		)
		(fp_line
			(start -4 -10.45)
			(end -4 0.05)
			(stroke
				(width 0.1)
				(type solid)
			)
			(layer "F.CrtYd")
		)
		(fp_line
			(start 17.8 -10.45)
			(end -4 -10.45)
			(stroke
				(width 0.1)
				(type solid)
			)
			(layer "F.CrtYd")
		)
		(pad "" np_thru_hole circle
			(at -2 -7.1 270)
			(size 4 4)
			(drill 3.03)
			(layers "*.Cu" "*.Mask")
		)
		(pad "" np_thru_hole circle
			(at 15.8 -7.1 270)
			(size 4 4)
			(drill 3.03)
			(layers "*.Cu" "*.Mask")
		)
		(pad "1" thru_hole circle
			(at 11.1 -2.9 270)
			(size 2.5 2.5)
			(drill 1.85)
			(layers "*.Cu" "*.Mask")
			(remove_unused_layers no)
			(net "+12V")
		)
		(pad "2" thru_hole circle
			(at 6.9 -2.9 270)
			(size 2.5 2.5)
			(drill 1.85)
			(layers "*.Cu" "*.Mask")
			(remove_unused_layers no)
			(net "+12V")
		)
		(pad "3" thru_hole circle
			(at 2.7 -2.9 270)
			(size 2.5 2.5)
			(drill 1.85)
			(layers "*.Cu" "*.Mask")
			(remove_unused_layers no)
			(net "+12V")
		)
		(pad "4" thru_hole circle
			(at 11.1 -7.1 270)
			(size 2.5 2.5)
			(drill 1.85)
			(layers "*.Cu" "*.Mask")
			(remove_unused_layers no)
			(net "GND")
		)
		(pad "5" thru_hole circle
			(at 6.9 -7.1 270)
			(size 2.5 2.5)
			(drill 1.85)
			(layers "*.Cu" "*.Mask")
			(remove_unused_layers no)
			(net "GND")
		)
		(pad "6" thru_hole circle
			(at 2.7 -7.1 270)
			(size 2.5 2.5)
			(drill 1.85)
			(layers "*.Cu" "*.Mask")
			(remove_unused_layers no)
			(net "GND")
		)
	)
	(footprint "discovery:CONN_02x04_4.2mm"
		(layer "F.Cu")
		(at 18 81.3 90)
		(property "Reference" "J1"
			(at 17.00276 1.07696 270)
			(layer "F.SilkS")
			(effects
				(font
					(size 1 1)
					(thickness 0.15)
				)
			)
		)
		(property "Value" "Conn_02x04_CPU"
			(at 10.69848 0.8509 90)
			(layer "F.Fab")
			(effects
				(font
					(size 1 1)
					(thickness 0.15)
				)
			)
		)
		(attr through_hole)
		(duplicate_pad_numbers_are_jumpers no)
		(fp_line
			(start 10.2 -11)
			(end 10.2 -9.6)
			(stroke
				(width 0.1)
				(type solid)
			)
			(layer "F.SilkS")
		)
		(fp_line
			(start 8.2 -11)
			(end 10.2 -11)
			(stroke
				(width 0.1)
				(type solid)
			)
			(layer "F.SilkS")
		)
		(fp_line
			(start 8.2 -11)
			(end 8.2 -9.6)
			(stroke
				(width 0.1)
				(type solid)
			)
			(layer "F.SilkS")
		)
		(fp_line
			(start 0 -9.6)
			(end 18 -9.6)
			(stroke
				(width 0.1)
				(type solid)
			)
			(layer "F.SilkS")
		)
		(fp_line
			(start 18 0)
			(end 18 -9.6)
			(stroke
				(width 0.1)
				(type solid)
			)
			(layer "F.SilkS")
		)
		(fp_line
			(start 0 0)
			(end 0 -9.6)
			(stroke
				(width 0.1)
				(type solid)
			)
			(layer "F.SilkS")
		)
		(fp_line
			(start 0 0)
			(end 18 0)
			(stroke
				(width 0.1)
				(type solid)
			)
			(layer "F.SilkS")
		)
		(fp_line
			(start 22 -11.05)
			(end -4 -11.05)
			(stroke
				(width 0.1)
				(type solid)
			)
			(layer "F.CrtYd")
		)
		(fp_line
			(start -4 -11.05)
			(end -4 0.1)
			(stroke
				(width 0.1)
				(type solid)
			)
			(layer "F.CrtYd")
		)
		(fp_line
			(start 22 0.1)
			(end 22 -11.05)
			(stroke
				(width 0.1)
				(type solid)
			)
			(layer "F.CrtYd")
		)
		(fp_line
			(start -4 0.1)
			(end 22 0.1)
			(stroke
				(width 0.1)
				(type solid)
			)
			(layer "F.CrtYd")
		)
		(pad "" np_thru_hole circle
			(at -2 -7.1 90)
			(size 4 4)
			(drill 3.03)
			(layers "*.Cu" "*.Mask")
		)
		(pad "" np_thru_hole circle
			(at 20 -7.1 90)
			(size 4 4)
			(drill 3.03)
			(layers "*.Cu" "*.Mask")
		)
		(pad "1" thru_hole circle
			(at 15.3 -2.7 90)
			(size 2.5 2.5)
			(drill 1.8)
			(layers "*.Cu" "*.Mask")
			(remove_unused_layers no)
			(net "GND")
		)
		(pad "2" thru_hole circle
			(at 11.1 -2.7 90)
			(size 2.5 2.5)
			(drill 1.8)
			(layers "*.Cu" "*.Mask")
			(remove_unused_layers no)
			(net "GND")
		)
		(pad "3" thru_hole circle
			(at 6.9 -2.7 90)
			(size 2.5 2.5)
			(drill 1.8)
			(layers "*.Cu" "*.Mask")
			(remove_unused_layers no)
			(net "GND")
		)
		(pad "4" thru_hole circle
			(at 2.7 -2.7 90)
			(size 2.5 2.5)
			(drill 1.8)
			(layers "*.Cu" "*.Mask")
			(remove_unused_layers no)
			(net "GND")
		)
		(pad "5" thru_hole circle
			(at 15.3 -6.9 90)
			(size 2.5 2.5)
			(drill 1.8)
			(layers "*.Cu" "*.Mask")
			(remove_unused_layers no)
			(net "+12V")
		)
		(pad "6" thru_hole circle
			(at 11.1 -6.9 90)
			(size 2.5 2.5)
			(drill 1.8)
			(layers "*.Cu" "*.Mask")
			(remove_unused_layers no)
			(net "+12V")
		)
		(pad "7" thru_hole circle
			(at 6.9 -6.9 90)
			(size 2.5 2.5)
			(drill 1.8)
			(layers "*.Cu" "*.Mask")
			(remove_unused_layers no)
			(net "+12V")
		)
		(pad "8" thru_hole circle
			(at 2.7 -6.9 90)
			(size 2.5 2.5)
			(drill 1.8)
			(layers "*.Cu" "*.Mask")
			(remove_unused_layers no)
			(net "+12V")
		)
	)
	(footprint "discovery:CONN_02x04_4.2mm"
		(layer "F.Cu")
		(at 28 63.3 -90)
		(property "Reference" "J3"
			(at 1.0922 0.97028 270)
			(layer "F.SilkS")
			(effects
				(font
					(size 1 1)
					(thickness 0.15)
				)
			)
		)
		(property "Value" "Conn_02x04_CPU"
			(at 10.69848 0.8509 270)
			(layer "F.Fab")
			(effects
				(font
					(size 1 1)
					(thickness 0.15)
				)
			)
		)
		(attr through_hole)
		(duplicate_pad_numbers_are_jumpers no)
		(fp_line
			(start 0 0)
			(end 18 0)
			(stroke
				(width 0.1)
				(type solid)
			)
			(layer "F.SilkS")
		)
		(fp_line
			(start 0 0)
			(end 0 -9.6)
			(stroke
				(width 0.1)
				(type solid)
			)
			(layer "F.SilkS")
		)
		(fp_line
			(start 18 0)
			(end 18 -9.6)
			(stroke
				(width 0.1)
				(type solid)
			)
			(layer "F.SilkS")
		)
		(fp_line
			(start 0 -9.6)
			(end 18 -9.6)
			(stroke
				(width 0.1)
				(type solid)
			)
			(layer "F.SilkS")
		)
		(fp_line
			(start 8.2 -11)
			(end 8.2 -9.6)
			(stroke
				(width 0.1)
				(type solid)
			)
			(layer "F.SilkS")
		)
		(fp_line
			(start 8.2 -11)
			(end 10.2 -11)
			(stroke
				(width 0.1)
				(type solid)
			)
			(layer "F.SilkS")
		)
		(fp_line
			(start 10.2 -11)
			(end 10.2 -9.6)
			(stroke
				(width 0.1)
				(type solid)
			)
			(layer "F.SilkS")
		)
		(fp_line
			(start -4 0.1)
			(end 22 0.1)
			(stroke
				(width 0.1)
				(type solid)
			)
			(layer "F.CrtYd")
		)
		(fp_line
			(start 22 0.1)
			(end 22 -11.05)
			(stroke
				(width 0.1)
				(type solid)
			)
			(layer "F.CrtYd")
		)
		(fp_line
			(start -4 -11.05)
			(end -4 0.1)
			(stroke
				(width 0.1)
				(type solid)
			)
			(layer "F.CrtYd")
		)
		(fp_line
			(start 22 -11.05)
			(end -4 -11.05)
			(stroke
				(width 0.1)
				(type solid)
			)
			(layer "F.CrtYd")
		)
		(pad "" np_thru_hole circle
			(at -2 -7.1 270)
			(size 4 4)
			(drill 3.03)
			(layers "*.Cu" "*.Mask")
		)
		(pad "" np_thru_hole circle
			(at 20 -7.1 270)
			(size 4 4)
			(drill 3.03)
			(layers "*.Cu" "*.Mask")
		)
		(pad "1" thru_hole circle
			(at 15.3 -2.7 270)
			(size 2.5 2.5)
			(drill 1.8)
			(layers "*.Cu" "*.Mask")
			(remove_unused_layers no)
			(net "GND")
		)
		(pad "2" thru_hole circle
			(at 11.1 -2.7 270)
			(size 2.5 2.5)
			(drill 1.8)
			(layers "*.Cu" "*.Mask")
			(remove_unused_layers no)
			(net "GND")
		)
		(pad "3" thru_hole circle
			(at 6.9 -2.7 270)
			(size 2.5 2.5)
			(drill 1.8)
			(layers "*.Cu" "*.Mask")
			(remove_unused_layers no)
			(net "GND")
		)
		(pad "4" thru_hole circle
			(at 2.7 -2.7 270)
			(size 2.5 2.5)
			(drill 1.8)
			(layers "*.Cu" "*.Mask")
			(remove_unused_layers no)
			(net "GND")
		)
		(pad "5" thru_hole circle
			(at 15.3 -6.9 270)
			(size 2.5 2.5)
			(drill 1.8)
			(layers "*.Cu" "*.Mask")
			(remove_unused_layers no)
			(net "+12V")
		)
		(pad "6" thru_hole circle
			(at 11.1 -6.9 270)
			(size 2.5 2.5)
			(drill 1.8)
			(layers "*.Cu" "*.Mask")
			(remove_unused_layers no)
			(net "+12V")
		)
		(pad "7" thru_hole circle
			(at 6.9 -6.9 270)
			(size 2.5 2.5)
			(drill 1.8)
			(layers "*.Cu" "*.Mask")
			(remove_unused_layers no)
			(net "+12V")
		)
		(pad "8" thru_hole circle
			(at 2.7 -6.9 270)
			(size 2.5 2.5)
			(drill 1.8)
			(layers "*.Cu" "*.Mask")
			(remove_unused_layers no)
			(net "+12V")
		)
	)
	(footprint "discovery:FixingPoint_Plated_Hole_D4.0mm"
		(layer "F.Cu")
		(at 145 145)
		(descr "Plated Hole as fixing Point, diameter 4.0mm")
		(tags "fixing point plated hole")
		(property "Reference" "W1"
			(at 3.81878 2.29224 0)
			(layer "F.SilkS")
			(effects
				(font
					(size 1 1)
					(thickness 0.15)
				)
			)
		)
		(property "Value" "Fixing hole"
			(at 0 3.55 0)
			(layer "F.Fab")
			(effects
				(font
					(size 1 1)
					(thickness 0.15)
				)
			)
		)
		(attr exclude_from_pos_files exclude_from_bom)
		(duplicate_pad_numbers_are_jumpers no)
		(fp_circle
			(center 0 0)
			(end 0 2.75)
			(stroke
				(width 0.12)
				(type solid)
			)
			(fill no)
			(layer "F.SilkS")
		)
		(fp_circle
			(center 0 0)
			(end 3 0)
			(stroke
				(width 0.05)
				(type solid)
			)
			(fill no)
			(layer "F.CrtYd")
		)
		(fp_text user "${REFERENCE}"
			(at 0 -3.55 0)
			(layer "F.Fab")
			(effects
				(font
					(size 1 1)
					(thickness 0.15)
				)
			)
		)
		(pad "1" thru_hole circle
			(at 0 0)
			(size 5 5)
			(drill 4)
			(layers "*.Cu" "*.Mask")
			(remove_unused_layers no)
			(net "GND")
		)
	)
	(footprint "discovery:FixingPoint_Plated_Hole_D4.0mm"
		(layer "F.Cu")
		(at 5 55)
		(descr "Plated Hole as fixing Point, diameter 4.0mm")
		(tags "fixing point plated hole")
		(property "Reference" "W2"
			(at 4.16432 -0.32904 0)
			(layer "F.SilkS")
			(effects
				(font
					(size 1 1)
					(thickness 0.15)
				)
			)
		)
		(property "Value" "Fixing hole"
			(at 0 3.55 0)
			(layer "F.Fab")
			(effects
				(font
					(size 1 1)
					(thickness 0.15)
				)
			)
		)
		(attr exclude_from_pos_files exclude_from_bom)
		(duplicate_pad_numbers_are_jumpers no)
		(fp_circle
			(center 0 0)
			(end 0 2.75)
			(stroke
				(width 0.12)
				(type solid)
			)
			(fill no)
			(layer "F.SilkS")
		)
		(fp_circle
			(center 0 0)
			(end 3 0)
			(stroke
				(width 0.05)
				(type solid)
			)
			(fill no)
			(layer "F.CrtYd")
		)
		(fp_text user "${REFERENCE}"
			(at 0 -3.55 0)
			(layer "F.Fab")
			(effects
				(font
					(size 1 1)
					(thickness 0.15)
				)
			)
		)
		(pad "1" thru_hole circle
			(at 0 0)
			(size 5 5)
			(drill 4)
			(layers "*.Cu" "*.Mask")
			(remove_unused_layers no)
			(net "GND")
		)
	)
	(footprint "discovery:FixingPoint_Plated_Hole_D4.0mm"
		(layer "F.Cu")
		(at 145 55)
		(descr "Plated Hole as fixing Point, diameter 4.0mm")
		(tags "fixing point plated hole")
		(property "Reference" "W3"
			(at 3.81878 2.29224 0)
			(layer "F.SilkS")
			(effects
				(font
					(size 1 1)
					(thickness 0.15)
				)
			)
		)
		(property "Value" "Fixing hole"
			(at 0 3.55 0)
			(layer "F.Fab")
			(effects
				(font
					(size 1 1)
					(thickness 0.15)
				)
			)
		)
		(attr exclude_from_pos_files exclude_from_bom)
		(duplicate_pad_numbers_are_jumpers no)
		(fp_circle
			(center 0 0)
			(end 0 2.75)
			(stroke
				(width 0.12)
				(type solid)
			)
			(fill no)
			(layer "F.SilkS")
		)
		(fp_circle
			(center 0 0)
			(end 3 0)
			(stroke
				(width 0.05)
				(type solid)
			)
			(fill no)
			(layer "F.CrtYd")
		)
		(fp_text user "${REFERENCE}"
			(at 0 -3.55 0)
			(layer "F.Fab")
			(effects
				(font
					(size 1 1)
					(thickness 0.15)
				)
			)
		)
		(pad "1" thru_hole circle
			(at 0 0)
			(size 5 5)
			(drill 4)
			(layers "*.Cu" "*.Mask")
			(remove_unused_layers no)
			(net "GND")
		)
	)
	(footprint "discovery:FixingPoint_Plated_Hole_D4.0mm"
		(layer "F.Cu")
		(at 5 145)
		(descr "Plated Hole as fixing Point, diameter 4.0mm")
		(tags "fixing point plated hole")
		(property "Reference" "W4"
			(at 3.81878 2.29224 0)
			(layer "F.SilkS")
			(effects
				(font
					(size 1 1)
					(thickness 0.15)
				)
			)
		)
		(property "Value" "Fixing hole"
			(at 0 3.55 0)
			(layer "F.Fab")
			(effects
				(font
					(size 1 1)
					(thickness 0.15)
				)
			)
		)
		(attr exclude_from_pos_files exclude_from_bom)
		(duplicate_pad_numbers_are_jumpers no)
		(fp_circle
			(center 0 0)
			(end 0 2.75)
			(stroke
				(width 0.12)
				(type solid)
			)
			(fill no)
			(layer "F.SilkS")
		)
		(fp_circle
			(center 0 0)
			(end 3 0)
			(stroke
				(width 0.05)
				(type solid)
			)
			(fill no)
			(layer "F.CrtYd")
		)
		(fp_text user "${REFERENCE}"
			(at 0 -3.55 0)
			(layer "F.Fab")
			(effects
				(font
					(size 1 1)
					(thickness 0.15)
				)
			)
		)
		(pad "1" thru_hole circle
			(at 0 0)
			(size 5 5)
			(drill 4)
			(layers "*.Cu" "*.Mask")
			(remove_unused_layers no)
			(net "GND")
		)
	)
	(footprint "discovery:fixing_hole"
		(layer "F.Cu")
		(at 60 67)
		(property "Reference" "W5"
			(at -4.4323 -7.4676 0)
			(layer "F.SilkS")
			(effects
				(font
					(size 1 1)
					(thickness 0.15)
				)
			)
		)
		(property "Value" "Cable hole"
			(at 5.3721 8.3312 0)
			(layer "F.Fab")
			(effects
				(font
					(size 1 1)
					(thickness 0.15)
				)
			)
		)
		(attr through_hole)
		(duplicate_pad_numbers_are_jumpers no)
		(fp_circle
			(center 0 0)
			(end 7.6 0)
			(stroke
				(width 0.1)
				(type solid)
			)
			(fill no)
			(layer "F.CrtYd")
		)
		(pad "1" thru_hole circle
			(at 0 0)
			(size 15 15)
			(drill 5.7)
			(layers "*.Cu" "*.Mask" "F.SilkS")
			(remove_unused_layers no)
			(net "+12V")
		)
	)
	(footprint "discovery:fixing_hole"
		(layer "F.Cu")
		(at 60 89.5)
		(property "Reference" "W6"
			(at -4.4323 -7.4676 0)
			(layer "F.SilkS")
			(effects
				(font
					(size 1 1)
					(thickness 0.15)
				)
			)
		)
		(property "Value" "Cable hole"
			(at 5.3721 8.3312 0)
			(layer "F.Fab")
			(effects
				(font
					(size 1 1)
					(thickness 0.15)
				)
			)
		)
		(attr through_hole)
		(duplicate_pad_numbers_are_jumpers no)
		(fp_circle
			(center 0 0)
			(end 7.6 0)
			(stroke
				(width 0.1)
				(type solid)
			)
			(fill no)
			(layer "F.CrtYd")
		)
		(pad "1" thru_hole circle
			(at 0 0)
			(size 15 15)
			(drill 5.7)
			(layers "*.Cu" "*.Mask" "F.SilkS")
			(remove_unused_layers no)
			(net "+12V")
		)
	)
	(footprint "discovery:fixing_hole"
		(layer "F.Cu")
		(at 60 112)
		(property "Reference" "W7"
			(at -4.4323 -7.4676 0)
			(layer "F.SilkS")
			(effects
				(font
					(size 1 1)
					(thickness 0.15)
				)
			)
		)
		(property "Value" "Cable hole"
			(at 5.3721 8.3312 0)
			(layer "F.Fab")
			(effects
				(font
					(size 1 1)
					(thickness 0.15)
				)
			)
		)
		(attr through_hole)
		(duplicate_pad_numbers_are_jumpers no)
		(fp_circle
			(center 0 0)
			(end 7.6 0)
			(stroke
				(width 0.1)
				(type solid)
			)
			(fill no)
			(layer "F.CrtYd")
		)
		(pad "1" thru_hole circle
			(at 0 0)
			(size 15 15)
			(drill 5.7)
			(layers "*.Cu" "*.Mask" "F.SilkS")
			(remove_unused_layers no)
			(net "+12V")
		)
	)
	(footprint "discovery:fixing_hole"
		(layer "F.Cu")
		(at 60 134.5)
		(property "Reference" "W8"
			(at -4.4323 -7.4676 0)
			(layer "F.SilkS")
			(effects
				(font
					(size 1 1)
					(thickness 0.15)
				)
			)
		)
		(property "Value" "Cable hole"
			(at 5.3721 8.3312 0)
			(layer "F.Fab")
			(effects
				(font
					(size 1 1)
					(thickness 0.15)
				)
			)
		)
		(attr through_hole)
		(duplicate_pad_numbers_are_jumpers no)
		(fp_circle
			(center 0 0)
			(end 7.6 0)
			(stroke
				(width 0.1)
				(type solid)
			)
			(fill no)
			(layer "F.CrtYd")
		)
		(pad "1" thru_hole circle
			(at 0 0)
			(size 15 15)
			(drill 5.7)
			(layers "*.Cu" "*.Mask" "F.SilkS")
			(remove_unused_layers no)
			(net "+12V")
		)
	)
	(footprint "discovery:fixing_hole"
		(layer "F.Cu")
		(at 120 64.25)
		(property "Reference" "W9"
			(at -4.4323 -7.4676 0)
			(layer "F.SilkS")
			(effects
				(font
					(size 1 1)
					(thickness 0.15)
				)
			)
		)
		(property "Value" "Cable hole"
			(at 5.3721 8.3312 0)
			(layer "F.Fab")
			(effects
				(font
					(size 1 1)
					(thickness 0.15)
				)
			)
		)
		(attr through_hole)
		(duplicate_pad_numbers_are_jumpers no)
		(fp_circle
			(center 0 0)
			(end 7.6 0)
			(stroke
				(width 0.1)
				(type solid)
			)
			(fill no)
			(layer "F.CrtYd")
		)
		(pad "1" thru_hole circle
			(at 0 0)
			(size 15 15)
			(drill 5.7)
			(layers "*.Cu" "*.Mask" "F.SilkS")
			(remove_unused_layers no)
			(net "GND")
		)
	)
	(footprint "discovery:fixing_hole"
		(layer "F.Cu")
		(at 120 86.75)
		(property "Reference" "W10"
			(at -4.4323 -7.4676 0)
			(layer "F.SilkS")
			(effects
				(font
					(size 1 1)
					(thickness 0.15)
				)
			)
		)
		(property "Value" "Cable hole"
			(at 5.3721 8.3312 0)
			(layer "F.Fab")
			(effects
				(font
					(size 1 1)
					(thickness 0.15)
				)
			)
		)
		(attr through_hole)
		(duplicate_pad_numbers_are_jumpers no)
		(fp_circle
			(center 0 0)
			(end 7.6 0)
			(stroke
				(width 0.1)
				(type solid)
			)
			(fill no)
			(layer "F.CrtYd")
		)
		(pad "1" thru_hole circle
			(at 0 0)
			(size 15 15)
			(drill 5.7)
			(layers "*.Cu" "*.Mask" "F.SilkS")
			(remove_unused_layers no)
			(net "GND")
		)
	)
	(footprint "discovery:fixing_hole"
		(layer "F.Cu")
		(at 120 131.75)
		(property "Reference" "W11"
			(at -4.4323 -7.4676 0)
			(layer "F.SilkS")
			(effects
				(font
					(size 1 1)
					(thickness 0.15)
				)
			)
		)
		(property "Value" "Cable hole"
			(at 5.3721 8.3312 0)
			(layer "F.Fab")
			(effects
				(font
					(size 1 1)
					(thickness 0.15)
				)
			)
		)
		(attr through_hole)
		(duplicate_pad_numbers_are_jumpers no)
		(fp_circle
			(center 0 0)
			(end 7.6 0)
			(stroke
				(width 0.1)
				(type solid)
			)
			(fill no)
			(layer "F.CrtYd")
		)
		(pad "1" thru_hole circle
			(at 0 0)
			(size 15 15)
			(drill 5.7)
			(layers "*.Cu" "*.Mask" "F.SilkS")
			(remove_unused_layers no)
			(net "GND")
		)
	)
	(footprint "discovery:fixing_hole"
		(layer "F.Cu")
		(at 120 109.25)
		(property "Reference" "W12"
			(at -4.4323 -7.4676 0)
			(layer "F.SilkS")
			(effects
				(font
					(size 1 1)
					(thickness 0.15)
				)
			)
		)
		(property "Value" "Cable hole"
			(at 5.3721 8.3312 0)
			(layer "F.Fab")
			(effects
				(font
					(size 1 1)
					(thickness 0.15)
				)
			)
		)
		(attr through_hole)
		(duplicate_pad_numbers_are_jumpers no)
		(fp_circle
			(center 0 0)
			(end 7.6 0)
			(stroke
				(width 0.1)
				(type solid)
			)
			(fill no)
			(layer "F.CrtYd")
		)
		(pad "1" thru_hole circle
			(at 0 0)
			(size 15 15)
			(drill 5.7)
			(layers "*.Cu" "*.Mask" "F.SilkS")
			(remove_unused_layers no)
			(net "GND")
		)
	)
	(gr_line
		(start 0 52)
		(end 2 50)
		(stroke
			(width 0.15)
			(type solid)
		)
		(layer "Edge.Cuts")
	)
	(gr_line
		(start 0 148)
		(end 0 52)
		(stroke
			(width 0.15)
			(type solid)
		)
		(layer "Edge.Cuts")
	)
	(gr_line
		(start 0 148)
		(end 2 150)
		(stroke
			(width 0.15)
			(type solid)
		)
		(layer "Edge.Cuts")
	)
	(gr_line
		(start 2 50)
		(end 148 50)
		(stroke
			(width 0.15)
			(type solid)
		)
		(layer "Edge.Cuts")
	)
	(gr_line
		(start 2 150)
		(end 148 150)
		(stroke
			(width 0.15)
			(type solid)
		)
		(layer "Edge.Cuts")
	)
	(gr_line
		(start 148 50)
		(end 150 52)
		(stroke
			(width 0.15)
			(type solid)
		)
		(layer "Edge.Cuts")
	)
	(gr_line
		(start 148 150)
		(end 150 148)
		(stroke
			(width 0.15)
			(type solid)
		)
		(layer "Edge.Cuts")
	)
	(gr_line
		(start 150 52)
		(end 150 148)
		(stroke
			(width 0.15)
			(type solid)
		)
		(layer "Edge.Cuts")
	)
	(zone
		(net "+12V")
		(layer "F.Cu")
		(hatch edge 0.508)
		(priority 1)
		(connect_pads
			(clearance 3)
		)
		(min_thickness 0.254)
		(fill yes
			(thermal_gap 0.255)
			(thermal_bridge_width 0.255)
			(island_removal_mode 0)
		)
		(polygon
			(pts
				(xy 105.39 62.25) (xy 105.39 138.17) (xy 110.28 143.06) (xy 126.82 143.06) (xy 132.6 137.28) (xy 132.6 57.27)
				(xy 128.48 53.07) (xy 108.73 53.13) (xy 105.32 56.45) (xy 105.32 62.24) (xy 105.37 62.24)
			)
		)
	)
	(zone
		(net "+12V")
		(layer "F.Cu")
		(hatch edge 0.508)
		(connect_pads
			(clearance 1)
		)
		(min_thickness 0.254)
		(fill yes
			(thermal_gap 0.255)
			(thermal_bridge_width 90)
			(island_removal_mode 0)
		)
		(polygon
			(pts
				(xy 151.93264 51.816) (xy 151.93264 147.7264) (xy 147.53336 152.12568) (xy 1.68656 152.12568) (xy -2.25552 148.1836)
				(xy -2.25552 51.37912) (xy 0.80264 48.26) (xy 148.37664 48.26)
			)
		)
	)
	(zone
		(net "GND")
		(layer "B.Cu")
		(hatch edge 0.508)
		(priority 1)
		(connect_pads
			(clearance 3)
		)
		(min_thickness 0.124)
		(fill yes
			(thermal_gap 0.125)
			(thermal_bridge_width 0.125)
			(island_removal_mode 0)
		)
		(polygon
			(pts
				(xy 44.16 69.88) (xy 44.16 144.73) (xy 46.38 146.92) (xy 73.88 146.92) (xy 76.08 144.73) (xy 76.08 62.59)
				(xy 68.86 55.17) (xy 51.31 55.21) (xy 44.89 61.77) (xy 44.04 62.62) (xy 44.04 69.89) (xy 44.12 69.89)
			)
		)
	)
	(zone
		(net "GND")
		(layer "B.Cu")
		(hatch edge 0.508)
		(connect_pads
			(clearance 1)
		)
		(min_thickness 0.254)
		(fill yes
			(thermal_gap 0.255)
			(thermal_bridge_width 90)
			(island_removal_mode 0)
		)
		(polygon
			(pts
				(xy 0.80264 48.26) (xy 148.37664 48.26) (xy 151.93264 51.816) (xy 151.93264 147.7264) (xy 147.53336 152.12568)
				(xy 1.68656 152.12568) (xy -2.25552 148.1836) (xy -2.25552 51.37912)
			)
		)
	)
)
